(kicad_pcb
	(version 20240108)
	(generator "pcbnew")
	(generator_version "8.0")
	(general
		(thickness 1.6)
		(legacy_teardrops no)
	)
	(paper "A4")
	(title_block
		(title "Jetson Orin Baseboard OCuLink Expansion")
		(date "2025-03-18")
		(rev "1.1.0")
		(company "Antmicro Ltd")
		(comment 1 "www.antmicro.com")
		(comment 9 "footprints 86-90 of 119")
	)
	(layers
		(0 "F.Cu" signal)
		(1 "In1.Cu" signal)
		(2 "In2.Cu" signal)
		(31 "B.Cu" signal)
		(32 "B.Adhes" user "B.Adhesive")
		(33 "F.Adhes" user "F.Adhesive")
		(34 "B.Paste" user)
		(35 "F.Paste" user)
		(36 "B.SilkS" user "B.Silkscreen")
		(37 "F.SilkS" user "F.Silkscreen")
		(38 "B.Mask" user)
		(39 "F.Mask" user)
		(40 "Dwgs.User" user "User.Drawings")
		(41 "Cmts.User" user "User.Comments")
		(42 "Eco1.User" user "User.Eco1")
		(43 "Eco2.User" user "User.Eco2")
		(44 "Edge.Cuts" user)
		(45 "Margin" user)
		(46 "B.CrtYd" user "B.Courtyard")
		(47 "F.CrtYd" user "F.Courtyard")
		(48 "B.Fab" user)
		(49 "F.Fab" user)
	)
	(footprint "antmicro-footprints:C_0402_1005Metric"
		(layer "B.Cu")
		(at 128.005 114.569251 90)
		(descr "Capacitor SMD 0402")
		(tags "capacitor SMD 0402")
		(property "Reference" "C7"
			(at 1.779251 -0.355 90)
			(layer "B.SilkS")
			(effects
				(font
					(size 0.7 0.7)
					(thickness 0.15)
				)
				(justify right top mirror)
			)
		)
		(property "Value" "C_100n_0402"
			(at -1.022927 -2.155213 90)
			(layer "B.Fab")
			(effects
				(font
					(size 0.7 0.7)
					(thickness 0.15)
				)
				(justify right top mirror)
			)
		)
		(property "Footprint" "antmicro-footprints:C_0402_1005Metric"
			(at 0 0 90)
			(layer "B.Fab")
			(hide yes)
			(effects
				(font
					(size 1.27 1.27)
					(thickness 0.15)
				)
				(justify mirror)
			)
		)
		(property "Datasheet" "https://www.murata.com/products/productdetail?partno=GRM155R61H104KE14%23"
			(at 0 0 90)
			(layer "B.Fab")
			(hide yes)
			(effects
				(font
					(size 1.27 1.27)
					(thickness 0.15)
				)
				(justify mirror)
			)
		)
		(property "Description" "SMD Multilayer Ceramic Capacitor, 0.1 µF, 50 V, 0402 [1005 Metric], ± 10%, X5R, GRM Series"
			(at 0 0 90)
			(layer "B.Fab")
			(hide yes)
			(effects
				(font
					(size 1.27 1.27)
					(thickness 0.15)
				)
				(justify mirror)
			)
		)
		(property "MPN" "GRM155R61H104KE14D"
			(at 0 0 -90)
			(unlocked yes)
			(layer "B.Fab")
			(hide yes)
			(effects
				(font
					(size 1 1)
					(thickness 0.15)
				)
				(justify mirror)
			)
		)
		(property "Manufacturer" "Murata"
			(at 0 0 -90)
			(unlocked yes)
			(layer "B.Fab")
			(hide yes)
			(effects
				(font
					(size 1 1)
					(thickness 0.15)
				)
				(justify mirror)
			)
		)
		(property "License" "Apache-2.0"
			(at 0 0 -90)
			(unlocked yes)
			(layer "B.Fab")
			(hide yes)
			(effects
				(font
					(size 1 1)
					(thickness 0.15)
				)
				(justify mirror)
			)
		)
		(property "Author" "Antmicro"
			(at 0 0 -90)
			(unlocked yes)
			(layer "B.Fab")
			(hide yes)
			(effects
				(font
					(size 1 1)
					(thickness 0.15)
				)
				(justify mirror)
			)
		)
		(property "Val" "100n"
			(at 0 0 -90)
			(unlocked yes)
			(layer "B.Fab")
			(hide yes)
			(effects
				(font
					(size 1 1)
					(thickness 0.15)
				)
				(justify mirror)
			)
		)
		(property "Voltage" "50V"
			(at 0 0 -90)
			(unlocked yes)
			(layer "B.Fab")
			(hide yes)
			(effects
				(font
					(size 1 1)
					(thickness 0.15)
				)
				(justify mirror)
			)
		)
		(property "Dielectric" "X5R"
			(at 0 0 -90)
			(unlocked yes)
			(layer "B.Fab")
			(hide yes)
			(effects
				(font
					(size 1 1)
					(thickness 0.15)
				)
				(justify mirror)
			)
		)
		(property "Public" "False"
			(at 0 0 -90)
			(unlocked yes)
			(layer "B.Fab")
			(hide yes)
			(effects
				(font
					(size 1 1)
					(thickness 0.15)
				)
				(justify mirror)
			)
		)
		(sheetname "Root")
		(sheetfile "jetson-orin-baseboard-oculink-expansion.kicad_sch")
		(attr smd)
		(fp_rect
			(start -0.925 0.47)
			(end 0.925 -0.47)
			(stroke
				(width 0.05)
				(type default)
			)
			(fill none)
			(layer "B.CrtYd")
		)
		(fp_line
			(start 0.504 -0.248)
			(end 0.504 0.25)
			(stroke
				(width 0.15)
				(type solid)
			)
			(layer "B.Fab")
		)
		(fp_line
			(start -0.494 -0.248)
			(end 0.504 -0.248)
			(stroke
				(width 0.15)
				(type solid)
			)
			(layer "B.Fab")
		)
		(fp_line
			(start 0.504 0.25)
			(end -0.494 0.25)
			(stroke
				(width 0.15)
				(type solid)
			)
			(layer "B.Fab")
		)
		(fp_line
			(start -0.494 0.25)
			(end -0.494 -0.248)
			(stroke
				(width 0.15)
				(type solid)
			)
			(layer "B.Fab")
		)
		(fp_text user "Author: Antmicro"
			(at -0.939 -3.399 90)
			(layer "B.Fab")
			(hide yes)
			(effects
				(font
					(size 0.7 0.7)
					(thickness 0.15)
				)
				(justify right top mirror)
			)
		)
		(fp_text user "License: Apache-2.0"
			(at -0.939 -5.799 90)
			(layer "B.Fab")
			(hide yes)
			(effects
				(font
					(size 0.7 0.7)
					(thickness 0.15)
				)
				(justify right top mirror)
			)
		)
		(fp_text user "${REFERENCE}"
			(at -0.939 -4.599 90)
			(layer "B.Fab")
			(hide yes)
			(effects
				(font
					(size 0.7 0.7)
					(thickness 0.15)
				)
				(justify right top mirror)
			)
		)
		(pad "1" smd roundrect
			(at -0.48 0 90)
			(size 0.59 0.64)
			(layers "B.Cu" "B.Paste" "B.Mask")
			(roundrect_rratio 0.25)
			(net 51 "GND")
			(pintype "passive")
		)
		(pad "2" smd roundrect
			(at 0.48 0 90)
			(size 0.59 0.64)
			(layers "B.Cu" "B.Paste" "B.Mask")
			(roundrect_rratio 0.25)
			(net 23 "+3V3")
			(pintype "passive")
		)
	)
	(footprint "antmicro-footprints:TP_SMD_1.5mm"
		(layer "B.Cu")
		(at 126.45 132.7 -90)
		(property "Reference" "TP1"
			(at 0.2495 -2.9365 0)
			(layer "B.SilkS")
			(hide yes)
			(effects
				(font
					(size 0.7 0.7)
					(thickness 0.15)
				)
				(justify left bottom mirror)
			)
		)
		(property "Value" "TP_1.5mm_SMD"
			(at 0 -1.7 90)
			(layer "B.Fab")
			(effects
				(font
					(size 0.7 0.7)
					(thickness 0.15)
				)
				(justify left bottom mirror)
			)
		)
		(property "Footprint" "antmicro-footprints:TP_SMD_1.5mm"
			(at 0 0 90)
			(layer "B.Fab")
			(hide yes)
			(effects
				(font
					(size 1.27 1.27)
					(thickness 0.15)
				)
				(justify mirror)
			)
		)
		(property "Description" "test point, SMT"
			(at 0 0 90)
			(layer "B.Fab")
			(hide yes)
			(effects
				(font
					(size 1.27 1.27)
					(thickness 0.15)
				)
				(justify mirror)
			)
		)
		(property "MPN" ""
			(at 0 0 90)
			(unlocked yes)
			(layer "B.Fab")
			(hide yes)
			(effects
				(font
					(size 1 1)
					(thickness 0.15)
				)
				(justify mirror)
			)
		)
		(property "Manufacturer" ""
			(at 0 0 90)
			(unlocked yes)
			(layer "B.Fab")
			(hide yes)
			(effects
				(font
					(size 1 1)
					(thickness 0.15)
				)
				(justify mirror)
			)
		)
		(property "Author" "Antmicro"
			(at 0 0 90)
			(unlocked yes)
			(layer "B.Fab")
			(hide yes)
			(effects
				(font
					(size 1 1)
					(thickness 0.15)
				)
				(justify mirror)
			)
		)
		(property "License" "Apache-2.0"
			(at 0 0 90)
			(unlocked yes)
			(layer "B.Fab")
			(hide yes)
			(effects
				(font
					(size 1 1)
					(thickness 0.15)
				)
				(justify mirror)
			)
		)
		(sheetname "Root")
		(sheetfile "jetson-orin-baseboard-oculink-expansion.kicad_sch")
		(attr exclude_from_pos_files exclude_from_bom)
		(fp_circle
			(center 0 0)
			(end 0.85 0)
			(stroke
				(width 0.05)
				(type default)
			)
			(fill none)
			(layer "B.CrtYd")
		)
		(fp_text user "${REFERENCE}"
			(at -0.7 -2.9 90)
			(layer "B.Fab")
			(hide yes)
			(effects
				(font
					(size 0.7 0.7)
					(thickness 0.15)
				)
				(justify left bottom mirror)
			)
		)
		(fp_text user "License: Apache-2.0"
			(at -0.7 -5.301 90)
			(layer "B.Fab")
			(hide yes)
			(effects
				(font
					(size 0.7 0.7)
					(thickness 0.15)
				)
				(justify left bottom mirror)
			)
		)
		(fp_text user "Author: Antmicro"
			(at -0.7 -4.101 90)
			(layer "B.Fab")
			(hide yes)
			(effects
				(font
					(size 0.7 0.7)
					(thickness 0.15)
				)
				(justify left bottom mirror)
			)
		)
		(pad "1" smd circle
			(at 0 0)
			(size 1.5 1.5)
			(layers "B.Cu" "B.Mask")
			(net 64 "/I2C_SCL")
			(pinfunction "1")
			(pintype "passive")
		)
	)
	(footprint "antmicro-footprints:R_0402_1005Metric"
		(layer "B.Cu")
		(at 129.794 126.66775 180)
		(descr "Resistor SMD 0402")
		(tags "resistor SMD 0402")
		(property "Reference" "R22"
			(at -3.336 -0.43225 0)
			(layer "B.SilkS")
			(effects
				(font
					(size 0.7 0.7)
					(thickness 0.15)
				)
				(justify left bottom mirror)
			)
		)
		(property "Value" "R_1k_0402"
			(at -1.011843 -1.772047 0)
			(layer "B.Fab")
			(effects
				(font
					(size 0.7 0.7)
					(thickness 0.15)
				)
				(justify left bottom mirror)
			)
		)
		(property "Footprint" "antmicro-footprints:R_0402_1005Metric"
			(at 0 0 0)
			(layer "B.Fab")
			(hide yes)
			(effects
				(font
					(size 1.27 1.27)
					(thickness 0.15)
				)
				(justify mirror)
			)
		)
		(property "Datasheet" "https://www.bourns.com/docs/product-datasheets/cr.pdf"
			(at 0 0 0)
			(layer "B.Fab")
			(hide yes)
			(effects
				(font
					(size 1.27 1.27)
					(thickness 0.15)
				)
				(justify mirror)
			)
		)
		(property "Description" "SMD Chip Resistor, 1 kohm, ± 1%, 63 mW, 0402 [1005 Metric], Thick Film, General Purpose"
			(at 0 0 0)
			(layer "B.Fab")
			(hide yes)
			(effects
				(font
					(size 1.27 1.27)
					(thickness 0.15)
				)
				(justify mirror)
			)
		)
		(property "MPN" "CR0402-FX-1001GLF"
			(at 0 0 0)
			(unlocked yes)
			(layer "B.Fab")
			(hide yes)
			(effects
				(font
					(size 1 1)
					(thickness 0.15)
				)
				(justify mirror)
			)
		)
		(property "Manufacturer" "Bourns"
			(at 0 0 0)
			(unlocked yes)
			(layer "B.Fab")
			(hide yes)
			(effects
				(font
					(size 1 1)
					(thickness 0.15)
				)
				(justify mirror)
			)
		)
		(property "License" "Apache-2.0"
			(at 0 0 0)
			(unlocked yes)
			(layer "B.Fab")
			(hide yes)
			(effects
				(font
					(size 1 1)
					(thickness 0.15)
				)
				(justify mirror)
			)
		)
		(property "Author" "Antmicro"
			(at 0 0 0)
			(unlocked yes)
			(layer "B.Fab")
			(hide yes)
			(effects
				(font
					(size 1 1)
					(thickness 0.15)
				)
				(justify mirror)
			)
		)
		(property "Val" "1k"
			(at 0 0 0)
			(unlocked yes)
			(layer "B.Fab")
			(hide yes)
			(effects
				(font
					(size 1 1)
					(thickness 0.15)
				)
				(justify mirror)
			)
		)
		(property "Tolerance" "1%"
			(at 0 0 0)
			(unlocked yes)
			(layer "B.Fab")
			(hide yes)
			(effects
				(font
					(size 1 1)
					(thickness 0.15)
				)
				(justify mirror)
			)
		)
		(property "Public" "False"
			(at 0 0 0)
			(unlocked yes)
			(layer "B.Fab")
			(hide yes)
			(effects
				(font
					(size 1 1)
					(thickness 0.15)
				)
				(justify mirror)
			)
		)
		(sheetname "Root")
		(sheetfile "jetson-orin-baseboard-oculink-expansion.kicad_sch")
		(attr smd dnp)
		(fp_rect
			(start -0.925 0.47)
			(end 0.925 -0.47)
			(stroke
				(width 0.05)
				(type default)
			)
			(fill none)
			(layer "B.CrtYd")
		)
		(fp_rect
			(start -0.5 0.25)
			(end 0.5 -0.25)
			(stroke
				(width 0.15)
				(type solid)
			)
			(fill none)
			(layer "B.Fab")
		)
		(fp_text user "License: Apache-2.0"
			(at -0.95 -5.169 0)
			(layer "B.Fab")
			(hide yes)
			(effects
				(font
					(size 0.7 0.7)
					(thickness 0.15)
				)
				(justify left bottom mirror)
			)
		)
		(fp_text user "Author: Antmicro"
			(at -0.95 -4.169 0)
			(layer "B.Fab")
			(hide yes)
			(effects
				(font
					(size 0.7 0.7)
					(thickness 0.15)
				)
				(justify left bottom mirror)
			)
		)
		(fp_text user "${REFERENCE}"
			(at -0.95 -3.168 0)
			(layer "B.Fab")
			(hide yes)
			(effects
				(font
					(size 0.7 0.7)
					(thickness 0.15)
				)
				(justify left bottom mirror)
			)
		)
		(pad "1" smd roundrect
			(at -0.48 0 180)
			(size 0.59 0.64)
			(layers "B.Cu" "B.Paste" "B.Mask")
			(roundrect_rratio 0.25)
			(net 51 "GND")
			(pintype "passive")
		)
		(pad "2" smd roundrect
			(at 0.48 0 180)
			(size 0.59 0.64)
			(layers "B.Cu" "B.Paste" "B.Mask")
			(roundrect_rratio 0.25)
			(net 98 "/TX_EQ1")
			(pintype "passive")
		)
	)
	(footprint "antmicro-footprints:C_0402_1005Metric"
		(layer "B.Cu")
		(at 124.275 125.795 90)
		(descr "Capacitor SMD 0402")
		(tags "capacitor SMD 0402")
		(property "Reference" "C18"
			(at 1.605 -0.555 90)
			(layer "B.SilkS")
			(effects
				(font
					(size 0.7 0.7)
					(thickness 0.15)
				)
				(justify right top mirror)
			)
		)
		(property "Value" "C_100n_0402"
			(at -1.022927 -2.155213 90)
			(layer "B.Fab")
			(effects
				(font
					(size 0.7 0.7)
					(thickness 0.15)
				)
				(justify right top mirror)
			)
		)
		(property "Footprint" "antmicro-footprints:C_0402_1005Metric"
			(at 0 0 90)
			(layer "B.Fab")
			(hide yes)
			(effects
				(font
					(size 1.27 1.27)
					(thickness 0.15)
				)
				(justify mirror)
			)
		)
		(property "Datasheet" "https://www.murata.com/products/productdetail?partno=GRM155R61H104KE14%23"
			(at 0 0 90)
			(layer "B.Fab")
			(hide yes)
			(effects
				(font
					(size 1.27 1.27)
					(thickness 0.15)
				)
				(justify mirror)
			)
		)
		(property "Description" "SMD Multilayer Ceramic Capacitor, 0.1 µF, 50 V, 0402 [1005 Metric], ± 10%, X5R, GRM Series"
			(at 0 0 90)
			(layer "B.Fab")
			(hide yes)
			(effects
				(font
					(size 1.27 1.27)
					(thickness 0.15)
				)
				(justify mirror)
			)
		)
		(property "MPN" "GRM155R61H104KE14D"
			(at 0 0 -90)
			(unlocked yes)
			(layer "B.Fab")
			(hide yes)
			(effects
				(font
					(size 1 1)
					(thickness 0.15)
				)
				(justify mirror)
			)
		)
		(property "Manufacturer" "Murata"
			(at 0 0 -90)
			(unlocked yes)
			(layer "B.Fab")
			(hide yes)
			(effects
				(font
					(size 1 1)
					(thickness 0.15)
				)
				(justify mirror)
			)
		)
		(property "License" "Apache-2.0"
			(at 0 0 -90)
			(unlocked yes)
			(layer "B.Fab")
			(hide yes)
			(effects
				(font
					(size 1 1)
					(thickness 0.15)
				)
				(justify mirror)
			)
		)
		(property "Author" "Antmicro"
			(at 0 0 -90)
			(unlocked yes)
			(layer "B.Fab")
			(hide yes)
			(effects
				(font
					(size 1 1)
					(thickness 0.15)
				)
				(justify mirror)
			)
		)
		(property "Val" "100n"
			(at 0 0 -90)
			(unlocked yes)
			(layer "B.Fab")
			(hide yes)
			(effects
				(font
					(size 1 1)
					(thickness 0.15)
				)
				(justify mirror)
			)
		)
		(property "Voltage" "50V"
			(at 0 0 -90)
			(unlocked yes)
			(layer "B.Fab")
			(hide yes)
			(effects
				(font
					(size 1 1)
					(thickness 0.15)
				)
				(justify mirror)
			)
		)
		(property "Dielectric" "X5R"
			(at 0 0 -90)
			(unlocked yes)
			(layer "B.Fab")
			(hide yes)
			(effects
				(font
					(size 1 1)
					(thickness 0.15)
				)
				(justify mirror)
			)
		)
		(property "Public" "False"
			(at 0 0 -90)
			(unlocked yes)
			(layer "B.Fab")
			(hide yes)
			(effects
				(font
					(size 1 1)
					(thickness 0.15)
				)
				(justify mirror)
			)
		)
		(sheetname "Root")
		(sheetfile "jetson-orin-baseboard-oculink-expansion.kicad_sch")
		(attr smd)
		(fp_rect
			(start -0.925 0.47)
			(end 0.925 -0.47)
			(stroke
				(width 0.05)
				(type default)
			)
			(fill none)
			(layer "B.CrtYd")
		)
		(fp_line
			(start 0.504 -0.248)
			(end 0.504 0.25)
			(stroke
				(width 0.15)
				(type solid)
			)
			(layer "B.Fab")
		)
		(fp_line
			(start -0.494 -0.248)
			(end 0.504 -0.248)
			(stroke
				(width 0.15)
				(type solid)
			)
			(layer "B.Fab")
		)
		(fp_line
			(start 0.504 0.25)
			(end -0.494 0.25)
			(stroke
				(width 0.15)
				(type solid)
			)
			(layer "B.Fab")
		)
		(fp_line
			(start -0.494 0.25)
			(end -0.494 -0.248)
			(stroke
				(width 0.15)
				(type solid)
			)
			(layer "B.Fab")
		)
		(fp_text user "${REFERENCE}"
			(at -0.939 -4.599 90)
			(layer "B.Fab")
			(hide yes)
			(effects
				(font
					(size 0.7 0.7)
					(thickness 0.15)
				)
				(justify right top mirror)
			)
		)
		(fp_text user "License: Apache-2.0"
			(at -0.939 -5.799 90)
			(layer "B.Fab")
			(hide yes)
			(effects
				(font
					(size 0.7 0.7)
					(thickness 0.15)
				)
				(justify right top mirror)
			)
		)
		(fp_text user "Author: Antmicro"
			(at -0.939 -3.399 90)
			(layer "B.Fab")
			(hide yes)
			(effects
				(font
					(size 0.7 0.7)
					(thickness 0.15)
				)
				(justify right top mirror)
			)
		)
		(pad "1" smd roundrect
			(at -0.48 0 90)
			(size 0.59 0.64)
			(layers "B.Cu" "B.Paste" "B.Mask")
			(roundrect_rratio 0.25)
			(net 51 "GND")
			(pintype "passive")
		)
		(pad "2" smd roundrect
			(at 0.48 0 90)
			(size 0.59 0.64)
			(layers "B.Cu" "B.Paste" "B.Mask")
			(roundrect_rratio 0.25)
			(net 23 "+3V3")
			(pintype "passive")
		)
	)
	(footprint "antmicro-footprints:R_0402_1005Metric"
		(layer "B.Cu")
		(at 116.55 128.28 180)
		(descr "Resistor SMD 0402")
		(tags "resistor SMD 0402")
		(property "Reference" "R34"
			(at 0.79 -0.19 0)
			(layer "B.SilkS")
			(effects
				(font
					(size 0.7 0.7)
					(thickness 0.15)
				)
				(justify left bottom mirror)
			)
		)
		(property "Value" "R_10k_0402"
			(at -1.011843 -1.772047 0)
			(layer "B.Fab")
			(effects
				(font
					(size 0.7 0.7)
					(thickness 0.15)
				)
				(justify left bottom mirror)
			)
		)
		(property "Footprint" "antmicro-footprints:R_0402_1005Metric"
			(at 0 0 0)
			(layer "B.Fab")
			(hide yes)
			(effects
				(font
					(size 1.27 1.27)
					(thickness 0.15)
				)
				(justify mirror)
			)
		)
		(property "Datasheet" "https://www.bourns.com/docs/product-datasheets/cr.pdf"
			(at 0 0 0)
			(layer "B.Fab")
			(hide yes)
			(effects
				(font
					(size 1.27 1.27)
					(thickness 0.15)
				)
				(justify mirror)
			)
		)
		(property "Description" "SMD Chip Resistor, 10 kohm, ± 1%, 62.5 mW, 0402 [1005 Metric], Thick Film, General Purpose"
			(at 0 0 0)
			(layer "B.Fab")
			(hide yes)
			(effects
				(font
					(size 1.27 1.27)
					(thickness 0.15)
				)
				(justify mirror)
			)
		)
		(property "MPN" "CR0402-FX-1002GLF"
			(at 0 0 0)
			(unlocked yes)
			(layer "B.Fab")
			(hide yes)
			(effects
				(font
					(size 1 1)
					(thickness 0.15)
				)
				(justify mirror)
			)
		)
		(property "Manufacturer" "Bourns"
			(at 0 0 0)
			(unlocked yes)
			(layer "B.Fab")
			(hide yes)
			(effects
				(font
					(size 1 1)
					(thickness 0.15)
				)
				(justify mirror)
			)
		)
		(property "License" "Apache-2.0"
			(at 0 0 0)
			(unlocked yes)
			(layer "B.Fab")
			(hide yes)
			(effects
				(font
					(size 1 1)
					(thickness 0.15)
				)
				(justify mirror)
			)
		)
		(property "Author" "Antmicro"
			(at 0 0 0)
			(unlocked yes)
			(layer "B.Fab")
			(hide yes)
			(effects
				(font
					(size 1 1)
					(thickness 0.15)
				)
				(justify mirror)
			)
		)
		(property "Val" "10k"
			(at 0 0 0)
			(unlocked yes)
			(layer "B.Fab")
			(hide yes)
			(effects
				(font
					(size 1 1)
					(thickness 0.15)
				)
				(justify mirror)
			)
		)
		(property "Tolerance" "1%"
			(at 0 0 0)
			(unlocked yes)
			(layer "B.Fab")
			(hide yes)
			(effects
				(font
					(size 1 1)
					(thickness 0.15)
				)
				(justify mirror)
			)
		)
		(sheetname "Root")
		(sheetfile "jetson-orin-baseboard-oculink-expansion.kicad_sch")
		(attr smd)
		(fp_rect
			(start -0.925 0.47)
			(end 0.925 -0.47)
			(stroke
				(width 0.05)
				(type default)
			)
			(fill none)
			(layer "B.CrtYd")
		)
		(fp_rect
			(start -0.5 0.25)
			(end 0.5 -0.25)
			(stroke
				(width 0.15)
				(type solid)
			)
			(fill none)
			(layer "B.Fab")
		)
		(fp_text user "${REFERENCE}"
			(at -0.95 -3.168 0)
			(layer "B.Fab")
			(hide yes)
			(effects
				(font
					(size 0.7 0.7)
					(thickness 0.15)
				)
				(justify left bottom mirror)
			)
		)
		(fp_text user "License: Apache-2.0"
			(at -0.95 -5.169 0)
			(layer "B.Fab")
			(hide yes)
			(effects
				(font
					(size 0.7 0.7)
					(thickness 0.15)
				)
				(justify left bottom mirror)
			)
		)
		(fp_text user "Author: Antmicro"
			(at -0.95 -4.169 0)
			(layer "B.Fab")
			(hide yes)
			(effects
				(font
					(size 0.7 0.7)
					(thickness 0.15)
				)
				(justify left bottom mirror)
			)
		)
		(pad "1" smd roundrect
			(at -0.48 0 180)
			(size 0.59 0.64)
			(layers "B.Cu" "B.Paste" "B.Mask")
			(roundrect_rratio 0.25)
			(net 51 "GND")
			(pintype "passive")
		)
		(pad "2" smd roundrect
			(at 0.48 0 180)
			(size 0.59 0.64)
			(layers "B.Cu" "B.Paste" "B.Mask")
			(roundrect_rratio 0.25)
			(net 105 "Net-(U3-EN_{I2C})")
			(pintype "passive")
		)
	)
)
